# T6G (Grand Teton) — schematic netlist excerpt (pin names and nets, part order shuffled) for the footprints in the layout excerpt that follows; sources: Cadence DE-HDL packaged netlist, KiCad conversion of 04192023_DAF0TMB3IC0_F0TG_MB_C_brd_V02_OCP.brd

R1474  Q_RES  10K 1% EMPTY  pkg 0402LF  page 169 : A = P12V_AUX_DSC_G2 ; B = GND

(kicad_pcb
	(version 20260206)
	(generator "pcbnew")
	(generator_version "10.0")
	(general
		(thickness 1.6)
		(legacy_teardrops no)
	)
	(paper "A4")
	(title_block
		(title "04192023_DAF0TMB3IC0_F0TG_MB_C_brd_V02_OCP.brd")
		(comment 1 "Grand Teton / footprints 801-801 of 8354")
	)
	(layers
		(0 "F.Cu" signal "TOP")
		(4 "In1.Cu" signal "GND")
		(6 "In2.Cu" signal "IN1")
		(8 "In3.Cu" signal "GND1")
		(10 "In4.Cu" signal "IN2")
		(12 "In5.Cu" signal "GND2")
		(14 "In6.Cu" signal "IN3")
		(16 "In7.Cu" signal "GND3")
		(18 "In8.Cu" signal "VCC")
		(20 "In9.Cu" signal "VCC1")
		(22 "In10.Cu" signal "GND4")
		(24 "In11.Cu" signal "IN4")
		(26 "In12.Cu" signal "GND5")
		(28 "In13.Cu" signal "IN5")
		(30 "In14.Cu" signal "GND6")
		(32 "In15.Cu" signal "IN6")
		(34 "In16.Cu" signal "GND7")
		(2 "B.Cu" signal "BOTTOM")
		(9 "F.Adhes" user "F.Adhesive")
		(11 "B.Adhes" user "B.Adhesive")
		(13 "F.Paste" user "Package Geometry/Pastemask Top")
		(15 "B.Paste" user "Package Geometry/Pastemask Bottom")
		(5 "F.SilkS" user "Ref Des/Silkscreen Top")
		(7 "B.SilkS" user "Ref Des/Silkscreen Bottom")
		(1 "F.Mask" user "Board Geometry/Soldermask Top")
		(3 "B.Mask" user "Board Geometry/Soldermask Bottom")
		(17 "Dwgs.User" user "User.Drawings")
		(19 "Cmts.User" user "User.Comments")
		(21 "Eco1.User" user "User.Eco1")
		(23 "Eco2.User" user "User.Eco2")
		(25 "Edge.Cuts" user "Board Geometry/Outline")
		(27 "Margin" user)
		(31 "F.CrtYd" user "Package Geometry/Place Bound Top")
		(29 "B.CrtYd" user "Package Geometry/Place Bound Bottom")
		(35 "F.Fab" user "Ref Des/Assembly Top")
		(33 "B.Fab" user "Ref Des/Assembly Bottom")
	)
	(footprint ""
		(layer "F.Cu")
		(at 38.9128 -111.45774 180)
		(property "Reference" "R1474"
			(at 0 0 180)
			(layer "F.SilkS")
			(hide yes)
			(effects
				(font
					(size 1.27 1.27)
				)
			)
		)
		(property "Value" ""
			(at 0 0 180)
			(layer "F.Fab")
			(effects
				(font
					(size 1.27 1.27)
				)
			)
		)
		(duplicate_pad_numbers_are_jumpers no)
		(fp_line
			(start 0.7874 0.4064)
			(end -0.7874 0.4064)
			(stroke
				(width 0.1524)
				(type default)
			)
			(layer "F.SilkS")
		)
		(fp_line
			(start 0.7874 -0.4064)
			(end 0.7874 0.4064)
			(stroke
				(width 0.1524)
				(type default)
			)
			(layer "F.SilkS")
		)
		(fp_line
			(start -0.7874 0.4064)
			(end -0.7874 -0.4064)
			(stroke
				(width 0.1524)
				(type default)
			)
			(layer "F.SilkS")
		)
		(fp_line
			(start -0.7874 -0.4064)
			(end 0.7874 -0.4064)
			(stroke
				(width 0.1524)
				(type default)
			)
			(layer "F.SilkS")
		)
		(fp_line
			(start 0.67945 0.3048)
			(end 0.120396 0.3048)
			(stroke
				(width 0.1)
				(type default)
			)
			(layer "F.Fab")
		)
		(fp_line
			(start 0.67945 -0.3048)
			(end 0.67945 0.3048)
			(stroke
				(width 0.1)
				(type default)
			)
			(layer "F.Fab")
		)
		(fp_line
			(start 0.12065 -0.2794)
			(end 0.12065 -0.3048)
			(stroke
				(width 0.1)
				(type default)
			)
			(layer "F.Fab")
		)
		(fp_line
			(start 0.12065 -0.3048)
			(end 0.67945 -0.3048)
			(stroke
				(width 0.1)
				(type default)
			)
			(layer "F.Fab")
		)
		(fp_line
			(start 0.120396 0.3048)
			(end 0.120396 0.2794)
			(stroke
				(width 0.1)
				(type default)
			)
			(layer "F.Fab")
		)
		(fp_line
			(start 0.120396 0.2794)
			(end -0.12065 0.2794)
			(stroke
				(width 0.1)
				(type default)
			)
			(layer "F.Fab")
		)
		(fp_line
			(start -0.12065 0.3048)
			(end -0.67945 0.3048)
			(stroke
				(width 0.1)
				(type default)
			)
			(layer "F.Fab")
		)
		(fp_line
			(start -0.12065 0.2794)
			(end -0.12065 0.3048)
			(stroke
				(width 0.1)
				(type default)
			)
			(layer "F.Fab")
		)
		(fp_line
			(start -0.12065 -0.2794)
			(end 0.12065 -0.2794)
			(stroke
				(width 0.1)
				(type default)
			)
			(layer "F.Fab")
		)
		(fp_line
			(start -0.12065 -0.305054)
			(end -0.12065 -0.2794)
			(stroke
				(width 0.1)
				(type default)
			)
			(layer "F.Fab")
		)
		(fp_line
			(start -0.67945 0.3048)
			(end -0.67945 -0.305054)
			(stroke
				(width 0.1)
				(type default)
			)
			(layer "F.Fab")
		)
		(fp_line
			(start -0.67945 -0.305054)
			(end -0.12065 -0.305054)
			(stroke
				(width 0.1)
				(type default)
			)
			(layer "F.Fab")
		)
		(pad "1" smd circle
			(at -0.40005 0 180)
			(size 0 0)
			(layers "F.Cu" "F.Mask" "F.Paste")
			(net "P12V_AUX_DSC_G2")
		)
		(pad "2" smd circle
			(at 0.40005 0 180)
			(size 0 0)
			(layers "F.Cu" "F.Mask" "F.Paste")
			(net "GND")
		)
	)
)
